# S9S_MB_2U (Grand Teton) — schematic netlist excerpt (pin names and nets, part order shuffled) for the footprints in the layout excerpt that follows; sources: Cadence DE-HDL packaged netlist, KiCad conversion of 03242023_DA0F0TMBIJ0_F0T_Motherboard_J_brd_V01_OCP.brd

J18  SCONN288_ADR50017P087CC  SCONN288_ADR50017-P087CC IO  pkg DDR288S_1-1VXB  page 99
  VIN_BULK0  = P12V_S3_AUX_CPU1_NVDIMM
  RFU0  = TP_CHA_CPU1_DIMM2_FRU_0
  VIN_MGMT  = P3V3_AUX
  HSCL  = I3C_SPD_DDRABCD_CPU1_LVC1_SCL_1
  HSDA  = I3C_SPD_DDRABCD_CPU1_LVC1_SDA
  VSS0  = GND
  DQ0_A  = M_A_CPU1_SA_DQ<0>
  VSS1  = GND
  DQ1_A  = M_A_CPU1_SA_DQ<1>
  VSS2  = GND
  DQS0_A_T  = M_A_CPU1_SA_DQS_DP<0>
  DQS0_A_C  = M_A_CPU1_SA_DQS_DN<0>
  VSS3  = GND
  DQ4_A  = M_A_CPU1_SA_DQ<4>
  VSS4  = GND
  DQ5_A  = M_A_CPU1_SA_DQ<5>
  VSS5  = GND
  DQ8_A  = M_A_CPU1_SA_DQ<8>
  VSS6  = GND
  DQ9_A  = M_A_CPU1_SA_DQ<9>
  VSS7  = GND
  DQS1_A_T  = M_A_CPU1_SA_DQS_DP<1>
  DQS1_A_C  = M_A_CPU1_SA_DQS_DN<1>
  VSS8  = GND
  DQ12_A  = M_A_CPU1_SA_DQ<12>
  VSS9  = GND
  DQ13_A  = M_A_CPU1_SA_DQ<13>
  VSS10  = GND
  DQ16_A  = M_A_CPU1_SA_DQ<16>
  VSS11  = GND
  DQ17_A  = M_A_CPU1_SA_DQ<17>
  VSS12  = GND
  DQS2_A_T  = M_A_CPU1_SA_DQS_DP<2>
  DQS2_A_C  = M_A_CPU1_SA_DQS_DN<2>
  VSS13  = GND
  DQ20_A  = M_A_CPU1_SA_DQ<20>
  VSS14  = GND
  DQ21_A  = M_A_CPU1_SA_DQ<21>
  VSS15  = GND
  DQ24_A  = M_A_CPU1_SA_DQ<24>
  VSS16  = GND
  DQ25_A  = M_A_CPU1_SA_DQ<25>
  VSS17  = GND
  DQS3_A_T  = M_A_CPU1_SA_DQS_DP<3>
  DQS3_A_C  = M_A_CPU1_SA_DQS_DN<3>
  VSS18  = GND
  DQ28_A  = M_A_CPU1_SA_DQ<28>
  VSS19  = GND
  DQ29_A  = M_A_CPU1_SA_DQ<29>
  VSS20  = GND
  CB0_A  = M_A_CPU1_SA_CB<0>
  VSS21  = GND
  CB1_A  = M_A_CPU1_SA_CB<1>
  VSS22  = GND
  DQS4_A_T  = M_A_CPU1_SA_DQS_DP<4>
  DQS4_A_C  = M_A_CPU1_SA_DQS_DN<4>
  VSS23  = GND
  CB4_A  = M_A_CPU1_SA_CB<4>
  VSS24  = GND
  CB5_A  = M_A_CPU1_SA_CB<5>
  VSS25  = GND
  ALERT_N  = M_A_CPU1_ALERT_N
  VSS26  = GND
  CS0_A_N  = M_A_CPU1_SA_CS_N<2>
  VSS27  = GND
  CA0_A  = M_A_CPU1_SA_CA<0>
  VSS28  = GND
  CA2_A  = M_A_CPU1_SA_CA<2>
  VSS29  = GND
  CA4_A  = M_A_CPU1_SA_CA<4>
  VSS30  = GND
  CA6_A  = M_A_CPU1_SA_CA<6>
  VSS31  = GND
  PAR_A  = M_A_CPU1_SA_PAR
  VSS32  = GND
  CA0_B  = M_A_CPU1_SB_CA<0>
  VSS33  = GND
  CA2_B  = M_A_CPU1_SB_CA<2>
  VSS34  = GND
  CA4_B  = M_A_CPU1_SB_CA<4>
  VSS35  = GND
  CA6_B  = M_A_CPU1_SB_CA<6>
  VSS36  = GND
  CS0_B_N  = M_A_CPU1_SB_CS_N<2>
  VSS37  = GND
  \lbd||rsp_a_n\  = M_A_CPU1_SA_RSP<1>
  \lbs||rsp_b_n\  = M_A_CPU1_SB_RSP<1>
  VSS38  = GND
  CB4_B  = M_A_CPU1_SB_CB<4>
  VSS39  = GND
  CB5_B  = M_A_CPU1_SB_CB<5>
  VSS40  = GND
  \dqs9_b_t||tdqs9_b_t||dbi4_b_n\  = M_A_CPU1_SB_DQS_DP<9>
  \dqs9_b_c||tdqs9_b_c\  = M_A_CPU1_SB_DQS_DN<9>
  VSS41  = GND
  CB0_B  = M_A_CPU1_SB_CB<0>
  VSS42  = GND
  CB1_B  = M_A_CPU1_SB_CB<1>
  VSS43  = GND
  DQ0_B  = M_A_CPU1_SB_DQ<0>
  VSS44  = GND
  DQ1_B  = M_A_CPU1_SB_DQ<1>
  VSS45  = GND
  DQS0_B_T  = M_A_CPU1_SB_DQS_DP<0>
  DQS0_B_C  = M_A_CPU1_SB_DQS_DN<0>
  VSS46  = GND
  DQ4_B  = M_A_CPU1_SB_DQ<4>
  VSS47  = GND
  DQ5_B  = M_A_CPU1_SB_DQ<5>
  VSS48  = GND
  DQ8_B  = M_A_CPU1_SB_DQ<8>
  VSS49  = GND
  DQ9_B  = M_A_CPU1_SB_DQ<9>
  VSS50  = GND
  DQS1_B_T  = M_A_CPU1_SB_DQS_DP<1>
  DQS1_B_C  = M_A_CPU1_SB_DQS_DN<1>
  VSS51  = GND
  DQ12_B  = M_A_CPU1_SB_DQ<12>
  VSS52  = GND
  DQ13_B  = M_A_CPU1_SB_DQ<13>
  VSS53  = GND
  DQ16_B  = M_A_CPU1_SB_DQ<16>
  VSS54  = GND
  DQ17_B  = M_A_CPU1_SB_DQ<17>
  VSS55  = GND
  DQS2_B_T  = M_A_CPU1_SB_DQS_DP<2>
  DQS2_B_C  = M_A_CPU1_SB_DQS_DN<2>
  VSS56  = GND
  DQ20_B  = M_A_CPU1_SB_DQ<20>
  VSS57  = GND
  DQ21_B  = M_A_CPU1_SB_DQ<21>
  VSS58  = GND
  DQ24_B  = M_A_CPU1_SB_DQ<24>
  VSS59  = GND
  DQ25_B  = M_A_CPU1_SB_DQ<25>
  VSS60  = GND
  DQS3_B_T  = M_A_CPU1_SB_DQS_DP<3>
  DQS3_B_C  = M_A_CPU1_SB_DQS_DN<3>
  VSS61  = GND
  DQ28_B  = M_A_CPU1_SB_DQ<28>
  VSS62  = GND
  DQ29_B  = M_A_CPU1_SB_DQ<29>
  VSS63  = GND
  RFU1  = TP_CHA_CPU1_DIMM2_FRU_1
  VIN_BULK1  = P12V_S3_AUX_CPU1_NVDIMM
  VIN_BULK2  = P12V_S3_AUX_CPU1_NVDIMM
  \pwr_good||fail_n\  = PWRGD_CHA_CPU1_DIMM2
  HSA  = PD_CHA_CPU1_DIMM2_SAA
  RFU2  = TP_CHA_CPU1_DIMM2_FRU_2
  RFU3  = TP_CHA_CPU1_DIMM2_FRU_3
  VSS64  = GND
  DQ2_A  = M_A_CPU1_SA_DQ<2>
  VSS65  = GND
  DQ3_A  = M_A_CPU1_SA_DQ<3>
  VSS66  = GND
  \dqs5_a_c||tdqs5_a_c||dqs5_a_t||tdqs5_a_t\  = M_A_CPU1_SA_DQS_DN<5>
  \dqs5_a_t||tdqs5_a_t\  = M_A_CPU1_SA_DQS_DP<5>
  VSS67  = GND
  DQ6_A  = M_A_CPU1_SA_DQ<6>
  VSS68  = GND
  DQ7_A  = M_A_CPU1_SA_DQ<7>
  VSS69  = GND
  DQ10_A  = M_A_CPU1_SA_DQ<10>
  VSS70  = GND
  DQ11_A  = M_A_CPU1_SA_DQ<11>
  VSS71  = GND
  \dqs6_a_c||tdqs6_a_c||dqs6_a_t||tdqs6_a_t\  = M_A_CPU1_SA_DQS_DN<6>
  \dqs6_a_t||tdqs6_a_t\  = M_A_CPU1_SA_DQS_DP<6>
  VSS72  = GND
  DQ14_A  = M_A_CPU1_SA_DQ<14>
  VSS73  = GND
  DQ15_A  = M_A_CPU1_SA_DQ<15>
  VSS74  = GND
  DQ18_A  = M_A_CPU1_SA_DQ<18>
  VSS75  = GND
  DQ19_A  = M_A_CPU1_SA_DQ<19>
  VSS76  = GND
  \dqs7_a_c||tdqs7_a_c\  = M_A_CPU1_SA_DQS_DN<7>
  \dqs7_a_t||tdqs7_a_t\  = M_A_CPU1_SA_DQS_DP<7>
  VSS77  = GND
  DQ22_A  = M_A_CPU1_SA_DQ<22>
  VSS78  = GND
  DQ23_A  = M_A_CPU1_SA_DQ<23>
  VSS79  = GND
  DQ26_A  = M_A_CPU1_SA_DQ<26>
  VSS80  = GND
  DQ27_A  = M_A_CPU1_SA_DQ<27>
  VSS81  = GND
  \dqs8_a_c||tdqs8_a_c\  = M_A_CPU1_SA_DQS_DN<8>
  \dqs8_a_t||tdqs8_a_t\  = M_A_CPU1_SA_DQS_DP<8>
  VSS82  = GND
  DQ30_A  = M_A_CPU1_SA_DQ<30>
  VSS83  = GND
  DQ31_A  = M_A_CPU1_SA_DQ<31>
  VSS84  = GND
  CB2_A  = M_A_CPU1_SA_CB<2>
  VSS85  = GND
  CB3_A  = M_A_CPU1_SA_CB<3>
  VSS86  = GND
  \dqs9_a_c||tdqs9_a_c\  = M_A_CPU1_SA_DQS_DN<9>
  \dqs9_a_t||tdqs9_a_t\  = M_A_CPU1_SA_DQS_DP<9>
  VSS87  = GND
  CB6_A  = M_A_CPU1_SA_CB<6>
  VSS88  = GND
  CB7_A  = M_A_CPU1_SA_CB<7>
  VSS89  = GND
  RESET_N  = RST_M_AB_CPU1_FPGA_N
  VSS90  = GND
  CS1_A_N  = M_A_CPU1_SA_CS_N<3>
  VSS91  = GND
  CA1_A  = M_A_CPU1_SA_CA<1>
  VSS92  = GND
  CA3_A  = M_A_CPU1_SA_CA<3>
  VSS93  = GND
  CA5_A  = M_A_CPU1_SA_CA<5>
  VSS94  = GND
  CK_T  = M_A_CPU1_CLK_DP<1>
  CK_C  = M_A_CPU1_CLK_DN<1>
  VSS95  = GND
  RFU4  = TP_CHA_CPU1_DIMM2_FRU_4
  CA1_B  = M_A_CPU1_SB_CA<1>
  VSS96  = GND
  CA3_B  = M_A_CPU1_SB_CA<3>
  VSS97  = GND
  CA5_B  = M_A_CPU1_SB_CA<5>
  VSS98  = GND
  PAR_B  = M_A_CPU1_SB_PAR
  VSS99  = GND
  CS1_B_N  = M_A_CPU1_SB_CS_N<3>
  VSS100  = GND
  RFU5  = TP_CHA_CPU1_DIMM2_FRU_5
  RFU6  = TP_CHA_CPU1_DIMM2_FRU_6
  VSS101  = GND
  CB6_B  = M_A_CPU1_SB_CB<6>
  VSS102  = GND
  CB7_B  = M_A_CPU1_SB_CB<7>
  VSS103  = GND
  DQS4_B_C  = M_A_CPU1_SB_DQS_DN<4>
  DQS4_B_T  = M_A_CPU1_SB_DQS_DP<4>
  VSS104  = GND
  CB2_B  = M_A_CPU1_SB_CB<2>
  VSS105  = GND
  CB3_B  = M_A_CPU1_SB_CB<3>
  VSS106  = GND
  DQ2_B  = M_A_CPU1_SB_DQ<2>
  VSS107  = GND
  DQ3_B  = M_A_CPU1_SB_DQ<3>
  VSS108  = GND
  \dqs5_b_c||tdqs5_b_c\  = M_A_CPU1_SB_DQS_DN<5>
  \dqs5_b_t||tdqs5_b_t\  = M_A_CPU1_SB_DQS_DP<5>
  VSS109  = GND
  DQ6_B  = M_A_CPU1_SB_DQ<6>
  VSS110  = GND
  DQ7_B  = M_A_CPU1_SB_DQ<7>
  VSS111  = GND
  DQ10_B  = M_A_CPU1_SB_DQ<10>
  VSS112  = GND
  DQ11_B  = M_A_CPU1_SB_DQ<11>
  VSS113  = GND
  \dqs6_b_c||tdqs6_b_c\  = M_A_CPU1_SB_DQS_DN<6>
  \dqs6_b_t||tdqs6_b_t\  = M_A_CPU1_SB_DQS_DP<6>
  VSS114  = GND
  DQ14_B  = M_A_CPU1_SB_DQ<14>
  VSS115  = GND
  DQ15_B  = M_A_CPU1_SB_DQ<15>
  VSS116  = GND
  DQ18_B  = M_A_CPU1_SB_DQ<18>
  VSS117  = GND
  DQ19_B  = M_A_CPU1_SB_DQ<19>
  VSS118  = GND
  \dqs7_b_c||tdqs7_b_c\  = M_A_CPU1_SB_DQS_DN<7>
  \dqs7_b_t||tdqs7_b_t\  = M_A_CPU1_SB_DQS_DP<7>
  VSS119  = GND
  DQ22_B  = M_A_CPU1_SB_DQ<22>
  VSS120  = GND
  DQ23_B  = M_A_CPU1_SB_DQ<23>
  VSS121  = GND
  DQ26_B  = M_A_CPU1_SB_DQ<26>
  VSS122  = GND
  DQ27_B  = M_A_CPU1_SB_DQ<27>
  VSS123  = GND
  \dqs8_b_c||tdqs8_b_c\  = M_A_CPU1_SB_DQS_DN<8>
  \dqs8_b_t||tdqs8_b_t\  = M_A_CPU1_SB_DQS_DP<8>
  VSS124  = GND
  DQ30_B  = M_A_CPU1_SB_DQ<30>
  VSS125  = GND
  DQ31_B  = M_A_CPU1_SB_DQ<31>
  VSS126  = GND
  G1  = GND
  G2  = GND
  G3  = GND

(kicad_pcb
	(version 20260206)
	(generator "pcbnew")
	(generator_version "10.0")
	(general
		(thickness 1.6)
		(legacy_teardrops no)
	)
	(paper "A4")
	(title_block
		(title "03242023_DA0F0TMBIJ0_F0T_Motherboard_J_brd_V01_OCP.brd")
		(comment 1 "Grand Teton / footprint 3819 of 6105 (J18), pads 138-182 of 291")
	)
	(layers
		(0 "F.Cu" signal "TOP")
		(4 "In1.Cu" signal "GND")
		(6 "In2.Cu" signal "IN1")
		(8 "In3.Cu" signal "GND1")
		(10 "In4.Cu" signal "IN2")
		(12 "In5.Cu" signal "GND2")
		(14 "In6.Cu" signal "IN3")
		(16 "In7.Cu" signal "GND3")
		(18 "In8.Cu" signal "VCC")
		(20 "In9.Cu" signal "VCC1")
		(22 "In10.Cu" signal "GND4")
		(24 "In11.Cu" signal "IN4")
		(26 "In12.Cu" signal "GND5")
		(28 "In13.Cu" signal "IN5")
		(30 "In14.Cu" signal "GND6")
		(32 "In15.Cu" signal "IN6")
		(34 "In16.Cu" signal "GND7")
		(2 "B.Cu" signal "BOTTOM")
		(9 "F.Adhes" user "F.Adhesive")
		(11 "B.Adhes" user "B.Adhesive")
		(13 "F.Paste" user "Package Geometry/Pastemask Top")
		(15 "B.Paste" user "Package Geometry/Pastemask Bottom")
		(5 "F.SilkS" user "Ref Des/Silkscreen Top")
		(7 "B.SilkS" user "Ref Des/Silkscreen Bottom")
		(1 "F.Mask" user "Board Geometry/Soldermask Top")
		(3 "B.Mask" user "Board Geometry/Soldermask Bottom")
		(17 "Dwgs.User" user "User.Drawings")
		(19 "Cmts.User" user "User.Comments")
		(21 "Eco1.User" user "User.Eco1")
		(23 "Eco2.User" user "User.Eco2")
		(25 "Edge.Cuts" user "Board Geometry/Outline")
		(27 "Margin" user)
		(31 "F.CrtYd" user "Package Geometry/Place Bound Top")
		(29 "B.CrtYd" user "Package Geometry/Place Bound Bottom")
		(35 "F.Fab" user "Ref Des/Assembly Top")
		(33 "B.Fab" user "Ref Des/Assembly Bottom")
	)
	(footprint ""
		(layer "F.Cu")
		(at 62.99708 -258.091686)
		(property "Reference" "J18"
			(at -1.547622 -81.836514 0)
			(unlocked yes)
			(layer "F.SilkS")
			(effects
				(font
					(size 0.7874 0.5842)
					(thickness 0.1524)
				)
				(justify left)
			)
		)
		(property "Value" ""
			(at 0 0 0)
			(layer "F.Fab")
			(effects
				(font
					(size 1.27 1.27)
				)
			)
		)
		(duplicate_pad_numbers_are_jumpers no)
		(pad "138" smd rect
			(at -2.050034 58.224928 270)
			(size 0.519938 1.4986)
			(layers "F.Cu" "F.Mask" "F.Paste")
			(net "M_A_CPU1_SB_DQS_DN<3>")
		)
		(pad "139" smd rect
			(at -2.050034 59.075066 270)
			(size 0.519938 1.4986)
			(layers "F.Cu" "F.Mask" "F.Paste")
			(net "GND")
		)
		(pad "140" smd rect
			(at -2.050034 59.92495 270)
			(size 0.519938 1.4986)
			(layers "F.Cu" "F.Mask" "F.Paste")
			(net "M_A_CPU1_SB_DQ<28>")
		)
		(pad "141" smd rect
			(at -2.050034 60.775088 270)
			(size 0.519938 1.4986)
			(layers "F.Cu" "F.Mask" "F.Paste")
			(net "GND")
		)
		(pad "142" smd rect
			(at -2.050034 61.624972 270)
			(size 0.519938 1.4986)
			(layers "F.Cu" "F.Mask" "F.Paste")
			(net "M_A_CPU1_SB_DQ<29>")
		)
		(pad "143" smd rect
			(at -2.050034 62.47511 270)
			(size 0.519938 1.4986)
			(layers "F.Cu" "F.Mask" "F.Paste")
			(net "GND")
		)
		(pad "144" smd rect
			(at -2.050034 63.324994 270)
			(size 0.519938 1.4986)
			(layers "F.Cu" "F.Mask" "F.Paste")
			(net "TP_CHA_CPU1_DIMM2_FRU_1")
		)
		(pad "145" smd rect
			(at 2.050034 -63.324994 270)
			(size 0.519938 1.4986)
			(layers "F.Cu" "F.Mask" "F.Paste")
			(net "P12V_S3_AUX_CPU1_NVDIMM")
		)
		(pad "146" smd rect
			(at 2.050034 -62.47511 270)
			(size 0.519938 1.4986)
			(layers "F.Cu" "F.Mask" "F.Paste")
			(net "P12V_S3_AUX_CPU1_NVDIMM")
		)
		(pad "147" smd rect
			(at 2.050034 -61.624972 270)
			(size 0.519938 1.4986)
			(layers "F.Cu" "F.Mask" "F.Paste")
			(net "PWRGD_CHA_CPU1_DIMM2")
		)
		(pad "148" smd rect
			(at 2.050034 -60.775088 270)
			(size 0.519938 1.4986)
			(layers "F.Cu" "F.Mask" "F.Paste")
			(net "PD_CHA_CPU1_DIMM2_SAA")
		)
		(pad "149" smd rect
			(at 2.050034 -59.92495 270)
			(size 0.519938 1.4986)
			(layers "F.Cu" "F.Mask" "F.Paste")
			(net "TP_CHA_CPU1_DIMM2_FRU_2")
		)
		(pad "150" smd rect
			(at 2.050034 -59.075066 270)
			(size 0.519938 1.4986)
			(layers "F.Cu" "F.Mask" "F.Paste")
			(net "TP_CHA_CPU1_DIMM2_FRU_3")
		)
		(pad "151" smd rect
			(at 2.050034 -58.224928 270)
			(size 0.519938 1.4986)
			(layers "F.Cu" "F.Mask" "F.Paste")
			(net "GND")
		)
		(pad "152" smd rect
			(at 2.050034 -57.375044 270)
			(size 0.519938 1.4986)
			(layers "F.Cu" "F.Mask" "F.Paste")
			(net "M_A_CPU1_SA_DQ<2>")
		)
		(pad "153" smd rect
			(at 2.050034 -56.524906 270)
			(size 0.519938 1.4986)
			(layers "F.Cu" "F.Mask" "F.Paste")
			(net "GND")
		)
		(pad "154" smd rect
			(at 2.050034 -55.675022 270)
			(size 0.519938 1.4986)
			(layers "F.Cu" "F.Mask" "F.Paste")
			(net "M_A_CPU1_SA_DQ<3>")
		)
		(pad "155" smd rect
			(at 2.050034 -54.824884 270)
			(size 0.519938 1.4986)
			(layers "F.Cu" "F.Mask" "F.Paste")
			(net "GND")
		)
		(pad "156" smd rect
			(at 2.050034 -53.975 270)
			(size 0.519938 1.4986)
			(layers "F.Cu" "F.Mask" "F.Paste")
			(net "M_A_CPU1_SA_DQS_DN<5>")
		)
		(pad "157" smd rect
			(at 2.050034 -53.125116 270)
			(size 0.519938 1.4986)
			(layers "F.Cu" "F.Mask" "F.Paste")
			(net "M_A_CPU1_SA_DQS_DP<5>")
		)
		(pad "158" smd rect
			(at 2.050034 -52.274978 270)
			(size 0.519938 1.4986)
			(layers "F.Cu" "F.Mask" "F.Paste")
			(net "GND")
		)
		(pad "159" smd rect
			(at 2.050034 -51.425094 270)
			(size 0.519938 1.4986)
			(layers "F.Cu" "F.Mask" "F.Paste")
			(net "M_A_CPU1_SA_DQ<6>")
		)
		(pad "160" smd rect
			(at 2.050034 -50.574956 270)
			(size 0.519938 1.4986)
			(layers "F.Cu" "F.Mask" "F.Paste")
			(net "GND")
		)
		(pad "161" smd rect
			(at 2.050034 -49.725072 270)
			(size 0.519938 1.4986)
			(layers "F.Cu" "F.Mask" "F.Paste")
			(net "M_A_CPU1_SA_DQ<7>")
		)
		(pad "162" smd rect
			(at 2.050034 -48.874934 270)
			(size 0.519938 1.4986)
			(layers "F.Cu" "F.Mask" "F.Paste")
			(net "GND")
		)
		(pad "163" smd rect
			(at 2.050034 -48.02505 270)
			(size 0.519938 1.4986)
			(layers "F.Cu" "F.Mask" "F.Paste")
			(net "M_A_CPU1_SA_DQ<10>")
		)
		(pad "164" smd rect
			(at 2.050034 -47.174912 270)
			(size 0.519938 1.4986)
			(layers "F.Cu" "F.Mask" "F.Paste")
			(net "GND")
		)
		(pad "165" smd rect
			(at 2.050034 -46.325028 270)
			(size 0.519938 1.4986)
			(layers "F.Cu" "F.Mask" "F.Paste")
			(net "M_A_CPU1_SA_DQ<11>")
		)
		(pad "166" smd rect
			(at 2.050034 -45.47489 270)
			(size 0.519938 1.4986)
			(layers "F.Cu" "F.Mask" "F.Paste")
			(net "GND")
		)
		(pad "167" smd rect
			(at 2.050034 -44.625006 270)
			(size 0.519938 1.4986)
			(layers "F.Cu" "F.Mask" "F.Paste")
			(net "M_A_CPU1_SA_DQS_DN<6>")
		)
		(pad "168" smd rect
			(at 2.050034 -43.775122 270)
			(size 0.519938 1.4986)
			(layers "F.Cu" "F.Mask" "F.Paste")
			(net "M_A_CPU1_SA_DQS_DP<6>")
		)
		(pad "169" smd rect
			(at 2.050034 -42.924984 270)
			(size 0.519938 1.4986)
			(layers "F.Cu" "F.Mask" "F.Paste")
			(net "GND")
		)
		(pad "170" smd rect
			(at 2.050034 -42.0751 270)
			(size 0.519938 1.4986)
			(layers "F.Cu" "F.Mask" "F.Paste")
			(net "M_A_CPU1_SA_DQ<14>")
		)
		(pad "171" smd rect
			(at 2.050034 -41.224962 270)
			(size 0.519938 1.4986)
			(layers "F.Cu" "F.Mask" "F.Paste")
			(net "GND")
		)
		(pad "172" smd rect
			(at 2.050034 -40.375078 270)
			(size 0.519938 1.4986)
			(layers "F.Cu" "F.Mask" "F.Paste")
			(net "M_A_CPU1_SA_DQ<15>")
		)
		(pad "173" smd rect
			(at 2.050034 -39.52494 270)
			(size 0.519938 1.4986)
			(layers "F.Cu" "F.Mask" "F.Paste")
			(net "GND")
		)
		(pad "174" smd rect
			(at 2.050034 -38.675056 270)
			(size 0.519938 1.4986)
			(layers "F.Cu" "F.Mask" "F.Paste")
			(net "M_A_CPU1_SA_DQ<18>")
		)
		(pad "175" smd rect
			(at 2.050034 -37.824918 270)
			(size 0.519938 1.4986)
			(layers "F.Cu" "F.Mask" "F.Paste")
			(net "GND")
		)
		(pad "176" smd rect
			(at 2.050034 -36.975034 270)
			(size 0.519938 1.4986)
			(layers "F.Cu" "F.Mask" "F.Paste")
			(net "M_A_CPU1_SA_DQ<19>")
		)
		(pad "177" smd rect
			(at 2.050034 -36.124896 270)
			(size 0.519938 1.4986)
			(layers "F.Cu" "F.Mask" "F.Paste")
			(net "GND")
		)
		(pad "178" smd rect
			(at 2.050034 -35.275012 270)
			(size 0.519938 1.4986)
			(layers "F.Cu" "F.Mask" "F.Paste")
			(net "M_A_CPU1_SA_DQS_DN<7>")
		)
		(pad "179" smd rect
			(at 2.050034 -34.425128 270)
			(size 0.519938 1.4986)
			(layers "F.Cu" "F.Mask" "F.Paste")
			(net "M_A_CPU1_SA_DQS_DP<7>")
		)
		(pad "180" smd rect
			(at 2.050034 -33.57499 270)
			(size 0.519938 1.4986)
			(layers "F.Cu" "F.Mask" "F.Paste")
			(net "GND")
		)
		(pad "181" smd rect
			(at 2.050034 -32.725106 270)
			(size 0.519938 1.4986)
			(layers "F.Cu" "F.Mask" "F.Paste")
			(net "M_A_CPU1_SA_DQ<22>")
		)
		(pad "182" smd rect
			(at 2.050034 -31.874968 270)
			(size 0.519938 1.4986)
			(layers "F.Cu" "F.Mask" "F.Paste")
			(net "GND")
		)
	)
)
